(kicad_pcb
	(version 20260206)
	(generator "pcbnew")
	(generator_version "10.0")
	(general
		(thickness 1.6)
		(legacy_teardrops no)
	)
	(paper "A4")
	(title_block
		(title "dpb — 14545-sa.0730WZS0815.brd")
		(comment 1 "Honey Badger (Wiwynn) / footprints 400-407 of 1066")
	)
	(layers
		(0 "F.Cu" signal "TOP")
		(4 "In1.Cu" signal "L2GND")
		(6 "In2.Cu" signal "L3")
		(8 "In3.Cu" signal "L4VCC")
		(10 "In4.Cu" signal "L5VCC")
		(12 "In5.Cu" signal "L6")
		(14 "In6.Cu" signal "L7GND")
		(2 "B.Cu" signal "BOTTOM")
		(9 "F.Adhes" user "F.Adhesive")
		(11 "B.Adhes" user "B.Adhesive")
		(13 "F.Paste" user "Package Geometry/Pastemask Top")
		(15 "B.Paste" user "Package Geometry/Pastemask Bottom")
		(5 "F.SilkS" user "Ref Des/Silkscreen Top")
		(7 "B.SilkS" user "Ref Des/Silkscreen Bottom")
		(1 "F.Mask" user "Board Geometry/Soldermask Top")
		(3 "B.Mask" user "Board Geometry/Soldermask Bottom")
		(17 "Dwgs.User" user "User.Drawings")
		(19 "Cmts.User" user "User.Comments")
		(21 "Eco1.User" user "User.Eco1")
		(23 "Eco2.User" user "User.Eco2")
		(25 "Edge.Cuts" user "Board Geometry/Outline")
		(27 "Margin" user)
		(31 "F.CrtYd" user "Package Geometry/Place Bound Top")
		(29 "B.CrtYd" user "Package Geometry/Place Bound Bottom")
		(35 "F.Fab" user "Ref Des/Assembly Top")
		(33 "B.Fab" user "Ref Des/Assembly Bottom")
	)
	(footprint ""
		(layer "F.Cu")
		(at 20.066 -397.9926)
		(property "Reference" "R507"
			(at 0 0 0)
			(layer "F.SilkS")
			(hide yes)
			(effects
				(font
					(size 1.27 1.27)
				)
			)
		)
		(property "Value" "0R2J-2-GP"
			(at 0.064008 -3.993896 0)
			(unlocked yes)
			(layer "F.Fab")
			(hide yes)
			(effects
				(font
					(size 1.016 1.016)
					(thickness 0.1524)
				)
			)
		)
		(property "Device Type" "R402H16"
			(at 0.064008 -5.517896 0)
			(unlocked yes)
			(layer "F.Fab")
			(hide yes)
			(effects
				(font
					(size 1.016 1.016)
					(thickness 0.1524)
				)
			)
		)
		(duplicate_pad_numbers_are_jumpers no)
		(fp_line
			(start -0.508 -0.9398)
			(end -0.508 0.9398)
			(stroke
				(width 0.1524)
				(type default)
			)
			(layer "F.SilkS")
		)
		(fp_line
			(start 0.508 -0.9398)
			(end -0.508 -0.9398)
			(stroke
				(width 0.1524)
				(type default)
			)
			(layer "F.SilkS")
		)
		(fp_rect
			(start -0.508 0.9398)
			(end 0.508 -0.9398)
			(stroke
				(width 0)
				(type default)
			)
			(fill no)
			(layer "F.CrtYd")
		)
		(fp_rect
			(start -0.508 0.9398)
			(end 0.508 -0.9398)
			(stroke
				(width 0)
				(type default)
			)
			(fill no)
			(layer "F.Fab")
		)
		(pad "1" smd custom
			(at 0 -0.4445)
			(size 0.1397 0.1397)
			(layers "F.Cu" "F.Mask" "F.Paste")
			(net "I2C_C_SDA_DAMP_A")
			(options
				(clearance outline)
				(anchor circle)
			)
			(primitives
				(gr_poly
					(pts
						(arc
							(start -0.1778 -0.2794)
							(mid -0.249642 -0.249642)
							(end -0.2794 -0.1778)
						)
						(arc
							(start -0.2794 0.1778)
							(mid -0.249642 0.249642)
							(end -0.1778 0.2794)
						)
						(arc
							(start 0.1778 0.2794)
							(mid 0.249642 0.249642)
							(end 0.2794 0.1778)
						)
						(arc
							(start 0.2794 -0.1778)
							(mid 0.249642 -0.249642)
							(end 0.1778 -0.2794)
						)
					)
					(width 0)
					(fill yes)
				)
			)
		)
		(pad "2" smd custom
			(at 0 0.4445)
			(size 0.1397 0.1397)
			(layers "F.Cu" "F.Mask" "F.Paste")
			(net "I2C_C_SDA")
			(options
				(clearance outline)
				(anchor circle)
			)
			(primitives
				(gr_poly
					(pts
						(arc
							(start -0.1778 -0.2794)
							(mid -0.249642 -0.249642)
							(end -0.2794 -0.1778)
						)
						(arc
							(start -0.2794 0.1778)
							(mid -0.249642 0.249642)
							(end -0.1778 0.2794)
						)
						(arc
							(start 0.1778 0.2794)
							(mid 0.249642 0.249642)
							(end 0.2794 0.1778)
						)
						(arc
							(start 0.2794 -0.1778)
							(mid 0.249642 -0.249642)
							(end 0.1778 -0.2794)
						)
					)
					(width 0)
					(fill yes)
				)
			)
		)
	)
	(footprint ""
		(layer "F.Cu")
		(at 34.035746 -422.938702 180)
		(property "Reference" "C271"
			(at 0 0 180)
			(layer "F.SilkS")
			(hide yes)
			(effects
				(font
					(size 1.27 1.27)
				)
			)
		)
		(property "Value" "SC10U25V6KX-1GP"
			(at -0.0762 -5.1308 180)
			(unlocked yes)
			(layer "F.Fab")
			(hide yes)
			(effects
				(font
					(size 1.016 1.016)
					(thickness 0.1524)
				)
			)
		)
		(property "Device Type" "C1206H71"
			(at -0.127 -6.6548 180)
			(unlocked yes)
			(layer "F.Fab")
			(hide yes)
			(effects
				(font
					(size 1.016 1.016)
					(thickness 0.1524)
				)
			)
		)
		(duplicate_pad_numbers_are_jumpers no)
		(fp_line
			(start 1.016 2.2352)
			(end -1.016 2.2352)
			(stroke
				(width 0.1524)
				(type default)
			)
			(layer "F.SilkS")
		)
		(fp_line
			(start 1.016 0.8382)
			(end 1.016 2.2352)
			(stroke
				(width 0.1524)
				(type default)
			)
			(layer "F.SilkS")
		)
		(fp_line
			(start 1.016 -2.2352)
			(end 1.016 -0.8382)
			(stroke
				(width 0.1524)
				(type default)
			)
			(layer "F.SilkS")
		)
		(fp_line
			(start -1.016 2.2352)
			(end -1.016 0.8382)
			(stroke
				(width 0.1524)
				(type default)
			)
			(layer "F.SilkS")
		)
		(fp_line
			(start -1.016 -0.8382)
			(end -1.016 -2.2352)
			(stroke
				(width 0.1524)
				(type default)
			)
			(layer "F.SilkS")
		)
		(fp_line
			(start -1.016 -2.2352)
			(end 1.016 -2.2352)
			(stroke
				(width 0.1524)
				(type default)
			)
			(layer "F.SilkS")
		)
		(fp_rect
			(start -1.0922 2.3114)
			(end 1.0922 -2.3114)
			(stroke
				(width 0)
				(type default)
			)
			(fill no)
			(layer "F.CrtYd")
		)
		(fp_poly
			(pts
				(xy 1.0922 -2.3114) (xy 1.0922 2.3114) (xy -1.0922 2.3114) (xy -1.0922 -2.3114)
			)
			(stroke
				(width 0)
				(type default)
			)
			(fill no)
			(layer "F.Fab")
		)
		(pad "1" smd rect
			(at 0 -1.397 180)
			(size 1.651 1.27)
			(layers "F.Cu" "F.Mask" "F.Paste")
			(net "P12V_HDD10")
		)
		(pad "2" smd rect
			(at 0 1.397 180)
			(size 1.651 1.27)
			(layers "F.Cu" "F.Mask" "F.Paste")
			(net "GND")
		)
	)
	(footprint ""
		(layer "F.Cu")
		(at 197.911974 -389.100822 -90)
		(property "Reference" "R429"
			(at 0 0 270)
			(layer "F.SilkS")
			(hide yes)
			(effects
				(font
					(size 1.27 1.27)
				)
			)
		)
		(property "Value" "4K7R2J-2-GP"
			(at 0.064008 -3.993896 270)
			(unlocked yes)
			(layer "F.Fab")
			(hide yes)
			(effects
				(font
					(size 1.016 1.016)
					(thickness 0.1524)
				)
			)
		)
		(property "Device Type" "R402H16"
			(at 0.064008 -5.517896 270)
			(unlocked yes)
			(layer "F.Fab")
			(hide yes)
			(effects
				(font
					(size 1.016 1.016)
					(thickness 0.1524)
				)
			)
		)
		(duplicate_pad_numbers_are_jumpers no)
		(fp_line
			(start -0.508 -0.9398)
			(end -0.508 0.9398)
			(stroke
				(width 0.1524)
				(type default)
			)
			(layer "F.SilkS")
		)
		(fp_line
			(start 0.508 -0.9398)
			(end -0.508 -0.9398)
			(stroke
				(width 0.1524)
				(type default)
			)
			(layer "F.SilkS")
		)
		(fp_rect
			(start -0.508 0.9398)
			(end 0.508 -0.9398)
			(stroke
				(width 0)
				(type default)
			)
			(fill no)
			(layer "F.CrtYd")
		)
		(fp_rect
			(start -0.508 0.9398)
			(end 0.508 -0.9398)
			(stroke
				(width 0)
				(type default)
			)
			(fill no)
			(layer "F.Fab")
		)
		(pad "1" smd custom
			(at 0 -0.4445 270)
			(size 0.1397 0.1397)
			(layers "F.Cu" "F.Mask" "F.Paste")
			(net "P3V3")
			(options
				(clearance outline)
				(anchor circle)
			)
			(primitives
				(gr_poly
					(pts
						(arc
							(start -0.1778 -0.2794)
							(mid -0.249642 -0.249642)
							(end -0.2794 -0.1778)
						)
						(arc
							(start -0.2794 0.1778)
							(mid -0.249642 0.249642)
							(end -0.1778 0.2794)
						)
						(arc
							(start 0.1778 0.2794)
							(mid 0.249642 0.249642)
							(end 0.2794 0.1778)
						)
						(arc
							(start 0.2794 -0.1778)
							(mid 0.249642 -0.249642)
							(end 0.1778 -0.2794)
						)
					)
					(width 0)
					(fill yes)
				)
			)
		)
		(pad "2" smd custom
			(at 0 0.4445 270)
			(size 0.1397 0.1397)
			(layers "F.Cu" "F.Mask" "F.Paste")
			(net "SAS_EXP_A_PWR1")
			(options
				(clearance outline)
				(anchor circle)
			)
			(primitives
				(gr_poly
					(pts
						(arc
							(start -0.1778 -0.2794)
							(mid -0.249642 -0.249642)
							(end -0.2794 -0.1778)
						)
						(arc
							(start -0.2794 0.1778)
							(mid -0.249642 0.249642)
							(end -0.1778 0.2794)
						)
						(arc
							(start 0.1778 0.2794)
							(mid 0.249642 0.249642)
							(end 0.2794 0.1778)
						)
						(arc
							(start 0.2794 -0.1778)
							(mid 0.249642 -0.249642)
							(end 0.1778 -0.2794)
						)
					)
					(width 0)
					(fill yes)
				)
			)
		)
	)
	(footprint ""
		(layer "F.Cu")
		(at 12.725146 -55.1434 90)
		(property "Reference" "R504"
			(at 0 0 90)
			(layer "F.SilkS")
			(hide yes)
			(effects
				(font
					(size 1.27 1.27)
				)
			)
		)
		(property "Value" "1KR2F-3-GP"
			(at 0.064008 -3.993896 90)
			(unlocked yes)
			(layer "F.Fab")
			(hide yes)
			(effects
				(font
					(size 1.016 1.016)
					(thickness 0.1524)
				)
			)
		)
		(property "Device Type" "R402H16"
			(at 0.064008 -5.517896 90)
			(unlocked yes)
			(layer "F.Fab")
			(hide yes)
			(effects
				(font
					(size 1.016 1.016)
					(thickness 0.1524)
				)
			)
		)
		(duplicate_pad_numbers_are_jumpers no)
		(fp_line
			(start 0.508 -0.9398)
			(end -0.508 -0.9398)
			(stroke
				(width 0.1524)
				(type default)
			)
			(layer "F.SilkS")
		)
		(fp_line
			(start -0.508 -0.9398)
			(end -0.508 0.9398)
			(stroke
				(width 0.1524)
				(type default)
			)
			(layer "F.SilkS")
		)
		(fp_rect
			(start -0.508 0.9398)
			(end 0.508 -0.9398)
			(stroke
				(width 0)
				(type default)
			)
			(fill no)
			(layer "F.CrtYd")
		)
		(fp_rect
			(start -0.508 0.9398)
			(end 0.508 -0.9398)
			(stroke
				(width 0)
				(type default)
			)
			(fill no)
			(layer "F.Fab")
		)
		(pad "1" smd custom
			(at 0 -0.4445 90)
			(size 0.1397 0.1397)
			(layers "F.Cu" "F.Mask" "F.Paste")
			(net "FLT_HDD14_B")
			(options
				(clearance outline)
				(anchor circle)
			)
			(primitives
				(gr_poly
					(pts
						(arc
							(start -0.1778 -0.2794)
							(mid -0.249642 -0.249642)
							(end -0.2794 -0.1778)
						)
						(arc
							(start -0.2794 0.1778)
							(mid -0.249642 0.249642)
							(end -0.1778 0.2794)
						)
						(arc
							(start 0.1778 0.2794)
							(mid 0.249642 0.249642)
							(end 0.2794 0.1778)
						)
						(arc
							(start 0.2794 -0.1778)
							(mid 0.249642 -0.249642)
							(end 0.1778 -0.2794)
						)
					)
					(width 0)
					(fill yes)
				)
			)
		)
		(pad "2" smd custom
			(at 0 0.4445 90)
			(size 0.1397 0.1397)
			(layers "F.Cu" "F.Mask" "F.Paste")
			(net "FLT_HDD14_DRIVE")
			(options
				(clearance outline)
				(anchor circle)
			)
			(primitives
				(gr_poly
					(pts
						(arc
							(start -0.1778 -0.2794)
							(mid -0.249642 -0.249642)
							(end -0.2794 -0.1778)
						)
						(arc
							(start -0.2794 0.1778)
							(mid -0.249642 0.249642)
							(end -0.1778 0.2794)
						)
						(arc
							(start 0.1778 0.2794)
							(mid 0.249642 0.249642)
							(end 0.2794 0.1778)
						)
						(arc
							(start 0.2794 -0.1778)
							(mid 0.249642 -0.249642)
							(end 0.1778 -0.2794)
						)
					)
					(width 0)
					(fill yes)
				)
			)
		)
	)
	(footprint ""
		(layer "F.Cu")
		(at 9.905746 -94.52864)
		(property "Reference" "TP6"
			(at 0 0 0)
			(layer "F.SilkS")
			(hide yes)
			(effects
				(font
					(size 1.27 1.27)
				)
			)
		)
		(property "Value" "TPAD32-GP"
			(at 0 -3.166364 0)
			(unlocked yes)
			(layer "F.Fab")
			(hide yes)
			(effects
				(font
					(size 1.016 1.016)
					(thickness 0.1524)
				)
			)
		)
		(property "Device Type" "TPAD32"
			(at 0 -4.690618 0)
			(unlocked yes)
			(layer "F.Fab")
			(hide yes)
			(effects
				(font
					(size 1.016 1.016)
					(thickness 0.1524)
				)
			)
		)
		(duplicate_pad_numbers_are_jumpers no)
		(fp_poly
			(pts
				(arc
					(start 0.4064 0)
					(mid -0.4064 0)
					(end 0.4064 0)
				)
			)
			(stroke
				(width 0)
				(type default)
			)
			(fill no)
			(layer "F.CrtYd")
		)
		(fp_poly
			(pts
				(arc
					(start 0.7112 0)
					(mid -0.7112 0)
					(end 0.7112 0)
				)
			)
			(stroke
				(width 0)
				(type default)
			)
			(fill no)
			(layer "F.Fab")
		)
		(pad "1" smd circle
			(at 0 0)
			(size 0.8128 0.8128)
			(layers "F.Cu" "F.Mask" "F.Paste")
			(net "SAS2X28_B_PRSNT15")
		)
	)
	(footprint ""
		(layer "F.Cu")
		(at 26.796746 -448.9577 90)
		(property "Reference" "C262"
			(at 0 0 90)
			(layer "F.SilkS")
			(hide yes)
			(effects
				(font
					(size 1.27 1.27)
				)
			)
		)
		(property "Value" "SCD01U50V2KX-1GP"
			(at 1.1811 -2.7051 90)
			(unlocked yes)
			(layer "F.Fab")
			(hide yes)
			(effects
				(font
					(size 1.016 1.016)
					(thickness 0.1524)
				)
			)
		)
		(property "Device Type" "C402H22"
			(at 1.1811 -4.2291 90)
			(unlocked yes)
			(layer "F.Fab")
			(hide yes)
			(effects
				(font
					(size 1.016 1.016)
					(thickness 0.1524)
				)
			)
		)
		(duplicate_pad_numbers_are_jumpers no)
		(fp_rect
			(start -0.4318 0.9525)
			(end 0.4318 -0.9525)
			(stroke
				(width 0)
				(type default)
			)
			(fill no)
			(layer "F.CrtYd")
		)
		(fp_rect
			(start -0.4318 0.9525)
			(end 0.4318 -0.9525)
			(stroke
				(width 0)
				(type default)
			)
			(fill no)
			(layer "F.Fab")
		)
		(pad "1" smd custom
			(at 0 -0.4445 90)
			(size 0.1524 0.1524)
			(layers "F.Cu" "F.Mask" "F.Paste")
			(net "SAS2X28_DRIVE_RX_N_A10")
			(options
				(clearance outline)
				(anchor circle)
			)
			(primitives
				(gr_poly
					(pts
						(arc
							(start 0.3048 -0.2032)
							(mid 0.275042 -0.275042)
							(end 0.2032 -0.3048)
						)
						(arc
							(start -0.2032 -0.3048)
							(mid -0.275042 -0.275042)
							(end -0.3048 -0.2032)
						)
						(arc
							(start -0.3048 0.2032)
							(mid -0.275042 0.275042)
							(end -0.2032 0.3048)
						)
						(arc
							(start 0.2032 0.3048)
							(mid 0.275042 0.275042)
							(end 0.3048 0.2032)
						)
					)
					(width 0)
					(fill yes)
				)
			)
		)
		(pad "2" smd custom
			(at 0 0.4445 90)
			(size 0.1524 0.1524)
			(layers "F.Cu" "F.Mask" "F.Paste")
			(net "SAS2X28_A_HDD10_RX_-")
			(options
				(clearance outline)
				(anchor circle)
			)
			(primitives
				(gr_poly
					(pts
						(arc
							(start 0.3048 -0.2032)
							(mid 0.275042 -0.275042)
							(end 0.2032 -0.3048)
						)
						(arc
							(start -0.2032 -0.3048)
							(mid -0.275042 -0.275042)
							(end -0.3048 -0.2032)
						)
						(arc
							(start -0.3048 0.2032)
							(mid -0.275042 0.275042)
							(end -0.2032 0.3048)
						)
						(arc
							(start 0.2032 0.3048)
							(mid 0.275042 0.275042)
							(end 0.3048 0.2032)
						)
					)
					(width 0)
					(fill yes)
				)
			)
		)
	)
	(footprint ""
		(layer "F.Cu")
		(at 215.221058 -381.405384 -90)
		(property "Reference" "R121"
			(at 0 0 270)
			(layer "F.SilkS")
			(hide yes)
			(effects
				(font
					(size 1.27 1.27)
				)
			)
		)
		(property "Value" "2R2010J-1-GP"
			(at 0.254 -8.0772 270)
			(unlocked yes)
			(layer "F.Fab")
			(hide yes)
			(effects
				(font
					(size 1.016 1.016)
					(thickness 0.1524)
				)
			)
		)
		(property "Device Type" "R2010H28"
			(at 0.254 -9.6774 270)
			(unlocked yes)
			(layer "F.Fab")
			(hide yes)
			(effects
				(font
					(size 1.016 1.016)
					(thickness 0.1524)
				)
			)
		)
		(duplicate_pad_numbers_are_jumpers no)
		(fp_line
			(start -1.651 3.302)
			(end 1.651 3.302)
			(stroke
				(width 0.1524)
				(type default)
			)
			(layer "F.SilkS")
		)
		(fp_line
			(start 1.651 3.302)
			(end 1.651 -3.302)
			(stroke
				(width 0.1524)
				(type default)
			)
			(layer "F.SilkS")
		)
		(fp_line
			(start -1.651 -3.302)
			(end -1.651 3.302)
			(stroke
				(width 0.1524)
				(type default)
			)
			(layer "F.SilkS")
		)
		(fp_line
			(start 1.651 -3.302)
			(end -1.651 -3.302)
			(stroke
				(width 0.1524)
				(type default)
			)
			(layer "F.SilkS")
		)
		(fp_rect
			(start -1.7272 -3.3782)
			(end 1.7272 3.3782)
			(stroke
				(width 0)
				(type default)
			)
			(fill no)
			(layer "F.CrtYd")
		)
		(fp_poly
			(pts
				(xy 1.7272 3.3782) (xy 1.7272 -3.3782) (xy -1.7272 -3.3782) (xy -1.7272 3.3782)
			)
			(stroke
				(width 0)
				(type default)
			)
			(fill no)
			(layer "F.Fab")
		)
		(pad "1" smd rect
			(at 0 -2.3495 270)
			(size 2.794 1.143)
			(layers "F.Cu" "F.Mask" "F.Paste")
			(net "5V_PRE_1")
		)
		(pad "2" smd rect
			(at 0 2.3495 270)
			(size 2.794 1.143)
			(layers "F.Cu" "F.Mask" "F.Paste")
			(net "P5V_HDD1")
		)
	)
	(footprint ""
		(layer "F.Cu")
		(at 203.245974 -391.894822 -90)
		(property "Reference" "R427"
			(at 0 0 270)
			(layer "F.SilkS")
			(hide yes)
			(effects
				(font
					(size 1.27 1.27)
				)
			)
		)
		(property "Value" "4K7R2J-2-GP"
			(at 0.064008 -3.993896 270)
			(unlocked yes)
			(layer "F.Fab")
			(hide yes)
			(effects
				(font
					(size 1.016 1.016)
					(thickness 0.1524)
				)
			)
		)
		(property "Device Type" "R402H16"
			(at 0.064008 -5.517896 270)
			(unlocked yes)
			(layer "F.Fab")
			(hide yes)
			(effects
				(font
					(size 1.016 1.016)
					(thickness 0.1524)
				)
			)
		)
		(duplicate_pad_numbers_are_jumpers no)
		(fp_line
			(start -0.508 -0.9398)
			(end -0.508 0.9398)
			(stroke
				(width 0.1524)
				(type default)
			)
			(layer "F.SilkS")
		)
		(fp_line
			(start 0.508 -0.9398)
			(end -0.508 -0.9398)
			(stroke
				(width 0.1524)
				(type default)
			)
			(layer "F.SilkS")
		)
		(fp_rect
			(start -0.508 0.9398)
			(end 0.508 -0.9398)
			(stroke
				(width 0)
				(type default)
			)
			(fill no)
			(layer "F.CrtYd")
		)
		(fp_rect
			(start -0.508 0.9398)
			(end 0.508 -0.9398)
			(stroke
				(width 0)
				(type default)
			)
			(fill no)
			(layer "F.Fab")
		)
		(pad "1" smd custom
			(at 0 -0.4445 270)
			(size 0.1397 0.1397)
			(layers "F.Cu" "F.Mask" "F.Paste")
			(net "P3V3")
			(options
				(clearance outline)
				(anchor circle)
			)
			(primitives
				(gr_poly
					(pts
						(arc
							(start -0.1778 -0.2794)
							(mid -0.249642 -0.249642)
							(end -0.2794 -0.1778)
						)
						(arc
							(start -0.2794 0.1778)
							(mid -0.249642 0.249642)
							(end -0.1778 0.2794)
						)
						(arc
							(start 0.1778 0.2794)
							(mid 0.249642 0.249642)
							(end 0.2794 0.1778)
						)
						(arc
							(start 0.2794 -0.1778)
							(mid 0.249642 -0.249642)
							(end 0.1778 -0.2794)
						)
					)
					(width 0)
					(fill yes)
				)
			)
		)
		(pad "2" smd custom
			(at 0 0.4445 270)
			(size 0.1397 0.1397)
			(layers "F.Cu" "F.Mask" "F.Paste")
			(net "SAS2X28_A_HDD1_FLT")
			(options
				(clearance outline)
				(anchor circle)
			)
			(primitives
				(gr_poly
					(pts
						(arc
							(start -0.1778 -0.2794)
							(mid -0.249642 -0.249642)
							(end -0.2794 -0.1778)
						)
						(arc
							(start -0.2794 0.1778)
							(mid -0.249642 0.249642)
							(end -0.1778 0.2794)
						)
						(arc
							(start 0.1778 0.2794)
							(mid 0.249642 0.249642)
							(end 0.2794 0.1778)
						)
						(arc
							(start 0.2794 -0.1778)
							(mid 0.249642 -0.249642)
							(end 0.1778 -0.2794)
						)
					)
					(width 0)
					(fill yes)
				)
			)
		)
	)
)
